# T6G (Grand Teton) — schematic netlist excerpt (pin names and nets, part order shuffled) for the footprints in the layout excerpt that follows; sources: Cadence DE-HDL packaged netlist, KiCad conversion of 04192023_DAF0TMB3IC0_F0TG_MB_C_brd_V02_OCP.brd

PR3932  Q_RES  4.99K 0.1% CHIP  pkg 0402LF  page 262 : A = HSC_VOSEN ; B = AGND_HSC
C407  Q_CAP  1UF 4V 20% X6S  pkg 0201  page 345 : A = P0V9_CPU1_RT2_2A ; B = GND
C326  Q_CAP  1UF 4V 20% X6S  pkg 0201  page 334 : A = P0V9_CPU1_RT1_2A ; B = GND
R6753  Q_RES  1K 1% CHIP  pkg 0201LF  page 184 : A = P1V8_CPU1_RT_1D ; B = SMB_RT_CPU1_P2_R_SCL

(kicad_pcb
	(version 20260206)
	(generator "pcbnew")
	(generator_version "10.0")
	(general
		(thickness 1.6)
		(legacy_teardrops no)
	)
	(paper "A4")
	(title_block
		(title "04192023_DAF0TMB3IC0_F0TG_MB_C_brd_V02_OCP.brd")
		(comment 1 "Grand Teton / footprints 7722-7725 of 8354")
	)
	(layers
		(0 "F.Cu" signal "TOP")
		(4 "In1.Cu" signal "GND")
		(6 "In2.Cu" signal "IN1")
		(8 "In3.Cu" signal "GND1")
		(10 "In4.Cu" signal "IN2")
		(12 "In5.Cu" signal "GND2")
		(14 "In6.Cu" signal "IN3")
		(16 "In7.Cu" signal "GND3")
		(18 "In8.Cu" signal "VCC")
		(20 "In9.Cu" signal "VCC1")
		(22 "In10.Cu" signal "GND4")
		(24 "In11.Cu" signal "IN4")
		(26 "In12.Cu" signal "GND5")
		(28 "In13.Cu" signal "IN5")
		(30 "In14.Cu" signal "GND6")
		(32 "In15.Cu" signal "IN6")
		(34 "In16.Cu" signal "GND7")
		(2 "B.Cu" signal "BOTTOM")
		(9 "F.Adhes" user "F.Adhesive")
		(11 "B.Adhes" user "B.Adhesive")
		(13 "F.Paste" user "Package Geometry/Pastemask Top")
		(15 "B.Paste" user "Package Geometry/Pastemask Bottom")
		(5 "F.SilkS" user "Ref Des/Silkscreen Top")
		(7 "B.SilkS" user "Ref Des/Silkscreen Bottom")
		(1 "F.Mask" user "Board Geometry/Soldermask Top")
		(3 "B.Mask" user "Board Geometry/Soldermask Bottom")
		(17 "Dwgs.User" user "User.Drawings")
		(19 "Cmts.User" user "User.Comments")
		(21 "Eco1.User" user "User.Eco1")
		(23 "Eco2.User" user "User.Eco2")
		(25 "Edge.Cuts" user "Board Geometry/Outline")
		(27 "Margin" user)
		(31 "F.CrtYd" user "Package Geometry/Place Bound Top")
		(29 "B.CrtYd" user "Package Geometry/Place Bound Bottom")
		(35 "F.Fab" user "Ref Des/Assembly Top")
		(33 "B.Fab" user "Ref Des/Assembly Bottom")
	)
	(footprint ""
		(layer "B.Cu")
		(at 147.00631 -386.766562 90)
		(property "Reference" "C407"
			(at 0 0 90)
			(layer "B.SilkS")
			(hide yes)
			(effects
				(font
					(size 1.27 1.27)
				)
				(justify mirror)
			)
		)
		(property "Value" ""
			(at 0 0 90)
			(layer "B.Fab")
			(effects
				(font
					(size 1.27 1.27)
				)
				(justify mirror)
			)
		)
		(duplicate_pad_numbers_are_jumpers no)
		(fp_line
			(start 0.299974 -0.150114)
			(end -0.299974 -0.150114)
			(stroke
				(width 0.1)
				(type default)
			)
			(layer "B.Fab")
		)
		(fp_line
			(start -0.299974 -0.150114)
			(end -0.299974 0.150114)
			(stroke
				(width 0.1)
				(type default)
			)
			(layer "B.Fab")
		)
		(fp_line
			(start 0.299974 0.150114)
			(end 0.299974 -0.150114)
			(stroke
				(width 0.1)
				(type default)
			)
			(layer "B.Fab")
		)
		(fp_line
			(start -0.299974 0.150114)
			(end 0.299974 0.150114)
			(stroke
				(width 0.1)
				(type default)
			)
			(layer "B.Fab")
		)
		(pad "1" smd rect
			(at 0.2667 0 270)
			(size 0.3048 0.381)
			(layers "B.Cu" "B.Mask" "B.Paste")
			(net "P0V9_CPU1_RT2_2A")
		)
		(pad "2" smd rect
			(at -0.2667 0 270)
			(size 0.3048 0.381)
			(layers "B.Cu" "B.Mask" "B.Paste")
			(net "GND")
		)
	)
	(footprint ""
		(layer "B.Cu")
		(at 216.916 -342.011 90)
		(property "Reference" "R6753"
			(at 0 0 90)
			(layer "B.SilkS")
			(hide yes)
			(effects
				(font
					(size 1.27 1.27)
				)
				(justify mirror)
			)
		)
		(property "Value" ""
			(at 0 0 90)
			(layer "B.Fab")
			(effects
				(font
					(size 1.27 1.27)
				)
				(justify mirror)
			)
		)
		(duplicate_pad_numbers_are_jumpers no)
		(fp_line
			(start 0.32512 -0.175006)
			(end -0.32512 -0.175006)
			(stroke
				(width 0.1)
				(type default)
			)
			(layer "B.Fab")
		)
		(fp_line
			(start -0.32512 -0.175006)
			(end -0.32512 0.175006)
			(stroke
				(width 0.1)
				(type default)
			)
			(layer "B.Fab")
		)
		(fp_line
			(start 0.32512 0.175006)
			(end 0.32512 -0.175006)
			(stroke
				(width 0.1)
				(type default)
			)
			(layer "B.Fab")
		)
		(fp_line
			(start -0.32512 0.175006)
			(end 0.32512 0.175006)
			(stroke
				(width 0.1)
				(type default)
			)
			(layer "B.Fab")
		)
		(pad "1" smd rect
			(at 0.2667 0 270)
			(size 0.3048 0.381)
			(layers "B.Cu" "B.Mask" "B.Paste")
			(net "P1V8_CPU1_RT_1D")
		)
		(pad "2" smd rect
			(at -0.2667 0 90)
			(size 0.3048 0.381)
			(layers "B.Cu" "B.Mask" "B.Paste")
			(net "SMB_RT_CPU1_P2_R_SCL")
		)
	)
	(footprint ""
		(layer "B.Cu")
		(at 79.906368 -386.766562 90)
		(property "Reference" "C326"
			(at 0 0 90)
			(layer "B.SilkS")
			(hide yes)
			(effects
				(font
					(size 1.27 1.27)
				)
				(justify mirror)
			)
		)
		(property "Value" ""
			(at 0 0 90)
			(layer "B.Fab")
			(effects
				(font
					(size 1.27 1.27)
				)
				(justify mirror)
			)
		)
		(duplicate_pad_numbers_are_jumpers no)
		(fp_line
			(start 0.299974 -0.150114)
			(end -0.299974 -0.150114)
			(stroke
				(width 0.1)
				(type default)
			)
			(layer "B.Fab")
		)
		(fp_line
			(start -0.299974 -0.150114)
			(end -0.299974 0.150114)
			(stroke
				(width 0.1)
				(type default)
			)
			(layer "B.Fab")
		)
		(fp_line
			(start 0.299974 0.150114)
			(end 0.299974 -0.150114)
			(stroke
				(width 0.1)
				(type default)
			)
			(layer "B.Fab")
		)
		(fp_line
			(start -0.299974 0.150114)
			(end 0.299974 0.150114)
			(stroke
				(width 0.1)
				(type default)
			)
			(layer "B.Fab")
		)
		(pad "1" smd rect
			(at 0.2667 0 270)
			(size 0.3048 0.381)
			(layers "B.Cu" "B.Mask" "B.Paste")
			(net "P0V9_CPU1_RT1_2A")
		)
		(pad "2" smd rect
			(at -0.2667 0 270)
			(size 0.3048 0.381)
			(layers "B.Cu" "B.Mask" "B.Paste")
			(net "GND")
		)
	)
	(footprint ""
		(layer "B.Cu")
		(at 183.164734 -399.867882)
		(property "Reference" "PR3932"
			(at 0 0 0)
			(layer "B.SilkS")
			(hide yes)
			(effects
				(font
					(size 1.27 1.27)
				)
				(justify mirror)
			)
		)
		(property "Value" ""
			(at 0 0 0)
			(layer "B.Fab")
			(effects
				(font
					(size 1.27 1.27)
				)
				(justify mirror)
			)
		)
		(duplicate_pad_numbers_are_jumpers no)
		(fp_line
			(start -0.7874 -0.4064)
			(end -0.7874 0.4064)
			(stroke
				(width 0.1524)
				(type default)
			)
			(layer "B.SilkS")
		)
		(fp_line
			(start -0.7874 0.4064)
			(end 0.7874 0.4064)
			(stroke
				(width 0.1524)
				(type default)
			)
			(layer "B.SilkS")
		)
		(fp_line
			(start 0.7874 -0.4064)
			(end -0.7874 -0.4064)
			(stroke
				(width 0.1524)
				(type default)
			)
			(layer "B.SilkS")
		)
		(fp_line
			(start 0.7874 0.4064)
			(end 0.7874 -0.4064)
			(stroke
				(width 0.1524)
				(type default)
			)
			(layer "B.SilkS")
		)
		(fp_line
			(start -0.67945 -0.3048)
			(end -0.67945 0.3048)
			(stroke
				(width 0.1)
				(type default)
			)
			(layer "B.Fab")
		)
		(fp_line
			(start -0.67945 0.3048)
			(end -0.120396 0.3048)
			(stroke
				(width 0.1)
				(type default)
			)
			(layer "B.Fab")
		)
		(fp_line
			(start -0.12065 -0.3048)
			(end -0.67945 -0.3048)
			(stroke
				(width 0.1)
				(type default)
			)
			(layer "B.Fab")
		)
		(fp_line
			(start -0.12065 -0.2794)
			(end -0.12065 -0.3048)
			(stroke
				(width 0.1)
				(type default)
			)
			(layer "B.Fab")
		)
		(fp_line
			(start -0.120396 0.2794)
			(end 0.12065 0.2794)
			(stroke
				(width 0.1)
				(type default)
			)
			(layer "B.Fab")
		)
		(fp_line
			(start -0.120396 0.3048)
			(end -0.120396 0.2794)
			(stroke
				(width 0.1)
				(type default)
			)
			(layer "B.Fab")
		)
		(fp_line
			(start 0.12065 -0.305054)
			(end 0.12065 -0.2794)
			(stroke
				(width 0.1)
				(type default)
			)
			(layer "B.Fab")
		)
		(fp_line
			(start 0.12065 -0.2794)
			(end -0.12065 -0.2794)
			(stroke
				(width 0.1)
				(type default)
			)
			(layer "B.Fab")
		)
		(fp_line
			(start 0.12065 0.2794)
			(end 0.12065 0.3048)
			(stroke
				(width 0.1)
				(type default)
			)
			(layer "B.Fab")
		)
		(fp_line
			(start 0.12065 0.3048)
			(end 0.67945 0.3048)
			(stroke
				(width 0.1)
				(type default)
			)
			(layer "B.Fab")
		)
		(fp_line
			(start 0.67945 -0.305054)
			(end 0.12065 -0.305054)
			(stroke
				(width 0.1)
				(type default)
			)
			(layer "B.Fab")
		)
		(fp_line
			(start 0.67945 0.3048)
			(end 0.67945 -0.305054)
			(stroke
				(width 0.1)
				(type default)
			)
			(layer "B.Fab")
		)
		(pad "1" smd circle
			(at 0.40005 0 180)
			(size 0 0)
			(layers "B.Cu" "B.Mask" "B.Paste")
			(net "HSC_VOSEN")
		)
		(pad "2" smd circle
			(at -0.40005 0 180)
			(size 0 0)
			(layers "B.Cu" "B.Mask" "B.Paste")
			(net "AGND_HSC")
		)
	)
)
